# T6G (Grand Teton) — schematic netlist excerpt (pin names and nets, part order shuffled) for the footprints in the layout excerpt that follows; sources: Cadence DE-HDL packaged netlist, KiCad conversion of 04192023_DAF0TMB3IC0_F0TG_MB_C_brd_V02_OCP.brd

C6745  Q_CAP_DIFFBUS  DIFF BUS_0.22UF 6.3V 20% X6S  pkg C0201  page 352 : \1\ = P5E_CPU1_P3_TX_BUF_C_DP<10> ; \2\ = P5E_CPU1_P3_TX_BUF_DP<10>
R6755  Q_RES  0 5% CHIP  pkg 0201LF  page 184 : A = SMB_RT_CPU0_P0_SCL ; B = SMB_RT_CPU0_P0_R_SCL
C211  Q_CAP  0.001UF 50V 10% EMPTY  pkg C0402  page 27 : A = JTAG_CPU0_TMS ; B = GND

(kicad_pcb
	(version 20260206)
	(generator "pcbnew")
	(generator_version "10.0")
	(general
		(thickness 1.6)
		(legacy_teardrops no)
	)
	(paper "A4")
	(title_block
		(title "04192023_DAF0TMB3IC0_F0TG_MB_C_brd_V02_OCP.brd")
		(comment 1 "Grand Teton / footprints 7812-7814 of 8354")
	)
	(layers
		(0 "F.Cu" signal "TOP")
		(4 "In1.Cu" signal "GND")
		(6 "In2.Cu" signal "IN1")
		(8 "In3.Cu" signal "GND1")
		(10 "In4.Cu" signal "IN2")
		(12 "In5.Cu" signal "GND2")
		(14 "In6.Cu" signal "IN3")
		(16 "In7.Cu" signal "GND3")
		(18 "In8.Cu" signal "VCC")
		(20 "In9.Cu" signal "VCC1")
		(22 "In10.Cu" signal "GND4")
		(24 "In11.Cu" signal "IN4")
		(26 "In12.Cu" signal "GND5")
		(28 "In13.Cu" signal "IN5")
		(30 "In14.Cu" signal "GND6")
		(32 "In15.Cu" signal "IN6")
		(34 "In16.Cu" signal "GND7")
		(2 "B.Cu" signal "BOTTOM")
		(9 "F.Adhes" user "F.Adhesive")
		(11 "B.Adhes" user "B.Adhesive")
		(13 "F.Paste" user "Package Geometry/Pastemask Top")
		(15 "B.Paste" user "Package Geometry/Pastemask Bottom")
		(5 "F.SilkS" user "Ref Des/Silkscreen Top")
		(7 "B.SilkS" user "Ref Des/Silkscreen Bottom")
		(1 "F.Mask" user "Board Geometry/Soldermask Top")
		(3 "B.Mask" user "Board Geometry/Soldermask Bottom")
		(17 "Dwgs.User" user "User.Drawings")
		(19 "Cmts.User" user "User.Comments")
		(21 "Eco1.User" user "User.Eco1")
		(23 "Eco2.User" user "User.Eco2")
		(25 "Edge.Cuts" user "Board Geometry/Outline")
		(27 "Margin" user)
		(31 "F.CrtYd" user "Package Geometry/Place Bound Top")
		(29 "B.CrtYd" user "Package Geometry/Place Bound Bottom")
		(35 "F.Fab" user "Ref Des/Assembly Top")
		(33 "B.Fab" user "Ref Des/Assembly Bottom")
	)
	(footprint ""
		(layer "B.Cu")
		(at 229.8446 -340.868 180)
		(property "Reference" "R6755"
			(at 0 0 0)
			(layer "B.SilkS")
			(hide yes)
			(effects
				(font
					(size 1.27 1.27)
				)
				(justify mirror)
			)
		)
		(property "Value" ""
			(at 0 0 0)
			(layer "B.Fab")
			(effects
				(font
					(size 1.27 1.27)
				)
				(justify mirror)
			)
		)
		(duplicate_pad_numbers_are_jumpers no)
		(fp_line
			(start 0.32512 0.175006)
			(end 0.32512 -0.175006)
			(stroke
				(width 0.1)
				(type default)
			)
			(layer "B.Fab")
		)
		(fp_line
			(start 0.32512 -0.175006)
			(end -0.32512 -0.175006)
			(stroke
				(width 0.1)
				(type default)
			)
			(layer "B.Fab")
		)
		(fp_line
			(start -0.32512 0.175006)
			(end 0.32512 0.175006)
			(stroke
				(width 0.1)
				(type default)
			)
			(layer "B.Fab")
		)
		(fp_line
			(start -0.32512 -0.175006)
			(end -0.32512 0.175006)
			(stroke
				(width 0.1)
				(type default)
			)
			(layer "B.Fab")
		)
		(pad "1" smd rect
			(at 0.2667 0)
			(size 0.3048 0.381)
			(layers "B.Cu" "B.Mask" "B.Paste")
			(net "SMB_RT_CPU0_P0_SCL")
		)
		(pad "2" smd rect
			(at -0.2667 0 180)
			(size 0.3048 0.381)
			(layers "B.Cu" "B.Mask" "B.Paste")
			(net "SMB_RT_CPU0_P0_R_SCL")
		)
	)
	(footprint ""
		(layer "B.Cu")
		(at 147.947126 -408.517344 90)
		(property "Reference" "C6745"
			(at 0 0 90)
			(layer "B.SilkS")
			(hide yes)
			(effects
				(font
					(size 1.27 1.27)
				)
				(justify mirror)
			)
		)
		(property "Value" ""
			(at 0 0 90)
			(layer "B.Fab")
			(effects
				(font
					(size 1.27 1.27)
				)
				(justify mirror)
			)
		)
		(duplicate_pad_numbers_are_jumpers no)
		(fp_line
			(start 0.299974 -0.150114)
			(end -0.299974 -0.150114)
			(stroke
				(width 0.1)
				(type default)
			)
			(layer "B.Fab")
		)
		(fp_line
			(start -0.299974 -0.150114)
			(end -0.299974 0.150114)
			(stroke
				(width 0.1)
				(type default)
			)
			(layer "B.Fab")
		)
		(fp_line
			(start 0.299974 0.150114)
			(end 0.299974 -0.150114)
			(stroke
				(width 0.1)
				(type default)
			)
			(layer "B.Fab")
		)
		(fp_line
			(start -0.299974 0.150114)
			(end 0.299974 0.150114)
			(stroke
				(width 0.1)
				(type default)
			)
			(layer "B.Fab")
		)
		(pad "1" smd rect
			(at 0.2667 0 270)
			(size 0.3048 0.381)
			(layers "B.Cu" "B.Mask" "B.Paste")
			(net "P5E_CPU1_P3_TX_BUF_C_DP<10>")
		)
		(pad "2" smd rect
			(at -0.2667 0 270)
			(size 0.3048 0.381)
			(layers "B.Cu" "B.Mask" "B.Paste")
			(net "P5E_CPU1_P3_TX_BUF_DP<10>")
		)
	)
	(footprint ""
		(layer "B.Cu")
		(at 379.520958 -208.530952 90)
		(property "Reference" "C211"
			(at 0 0 90)
			(layer "B.SilkS")
			(hide yes)
			(effects
				(font
					(size 1.27 1.27)
				)
				(justify mirror)
			)
		)
		(property "Value" ""
			(at 0 0 90)
			(layer "B.Fab")
			(effects
				(font
					(size 1.27 1.27)
				)
				(justify mirror)
			)
		)
		(duplicate_pad_numbers_are_jumpers no)
		(fp_line
			(start 0.7874 -0.4064)
			(end -0.7874 -0.4064)
			(stroke
				(width 0.1524)
				(type default)
			)
			(layer "B.SilkS")
		)
		(fp_line
			(start -0.7874 -0.4064)
			(end -0.7874 0.4064)
			(stroke
				(width 0.1524)
				(type default)
			)
			(layer "B.SilkS")
		)
		(fp_line
			(start 0.7874 0.4064)
			(end 0.7874 -0.4064)
			(stroke
				(width 0.1524)
				(type default)
			)
			(layer "B.SilkS")
		)
		(fp_line
			(start -0.7874 0.4064)
			(end 0.7874 0.4064)
			(stroke
				(width 0.1524)
				(type default)
			)
			(layer "B.SilkS")
		)
		(fp_line
			(start 0.67945 -0.305054)
			(end 0.12065 -0.305054)
			(stroke
				(width 0.1)
				(type default)
			)
			(layer "B.Fab")
		)
		(fp_line
			(start 0.12065 -0.305054)
			(end 0.12065 -0.2794)
			(stroke
				(width 0.1)
				(type default)
			)
			(layer "B.Fab")
		)
		(fp_line
			(start -0.12065 -0.3048)
			(end -0.67945 -0.3048)
			(stroke
				(width 0.1)
				(type default)
			)
			(layer "B.Fab")
		)
		(fp_line
			(start -0.67945 -0.3048)
			(end -0.67945 0.3048)
			(stroke
				(width 0.1)
				(type default)
			)
			(layer "B.Fab")
		)
		(fp_line
			(start 0.12065 -0.2794)
			(end -0.12065 -0.2794)
			(stroke
				(width 0.1)
				(type default)
			)
			(layer "B.Fab")
		)
		(fp_line
			(start -0.12065 -0.2794)
			(end -0.12065 -0.3048)
			(stroke
				(width 0.1)
				(type default)
			)
			(layer "B.Fab")
		)
		(fp_line
			(start 0.12065 0.2794)
			(end 0.12065 0.3048)
			(stroke
				(width 0.1)
				(type default)
			)
			(layer "B.Fab")
		)
		(fp_line
			(start -0.120396 0.2794)
			(end 0.12065 0.2794)
			(stroke
				(width 0.1)
				(type default)
			)
			(layer "B.Fab")
		)
		(fp_line
			(start 0.67945 0.3048)
			(end 0.67945 -0.305054)
			(stroke
				(width 0.1)
				(type default)
			)
			(layer "B.Fab")
		)
		(fp_line
			(start 0.12065 0.3048)
			(end 0.67945 0.3048)
			(stroke
				(width 0.1)
				(type default)
			)
			(layer "B.Fab")
		)
		(fp_line
			(start -0.120396 0.3048)
			(end -0.120396 0.2794)
			(stroke
				(width 0.1)
				(type default)
			)
			(layer "B.Fab")
		)
		(fp_line
			(start -0.67945 0.3048)
			(end -0.120396 0.3048)
			(stroke
				(width 0.1)
				(type default)
			)
			(layer "B.Fab")
		)
		(pad "1" smd circle
			(at 0.40005 0 270)
			(size 0 0)
			(layers "B.Cu" "B.Mask" "B.Paste")
			(net "JTAG_CPU0_TMS")
		)
		(pad "2" smd circle
			(at -0.40005 0 270)
			(size 0 0)
			(layers "B.Cu" "B.Mask" "B.Paste")
			(net "GND")
		)
	)
)
